(kicad_pcb
	(version 20241229)
	(generator "pcbnew")
	(generator_version "9.0")
	(general
		(thickness 1.62)
		(legacy_teardrops no)
	)
	(paper "A4")
	(title_block
		(title "OCuLink to 10GbE adapter")
		(date "2026-02-23")
		(rev "1.1.0")
		(company "Antmicro Ltd")
		(comment 1 "www.antmicro.com")
		(comment 9 "footprint 265 of 510 (U9), pads 401-479 of 503")
	)
	(layers
		(0 "F.Cu" signal)
		(4 "In1.Cu" signal)
		(6 "In2.Cu" signal)
		(8 "In3.Cu" signal)
		(10 "In4.Cu" signal)
		(12 "In5.Cu" signal)
		(14 "In6.Cu" signal)
		(2 "B.Cu" signal)
		(9 "F.Adhes" user "F.Adhesive")
		(11 "B.Adhes" user "B.Adhesive")
		(13 "F.Paste" user)
		(15 "B.Paste" user)
		(5 "F.SilkS" user "F.Silkscreen")
		(7 "B.SilkS" user "B.Silkscreen")
		(1 "F.Mask" user)
		(3 "B.Mask" user)
		(17 "Dwgs.User" user "User.Drawings")
		(19 "Cmts.User" user "User.Comments")
		(21 "Eco1.User" user "User.Eco1")
		(23 "Eco2.User" user "User.Eco2")
		(25 "Edge.Cuts" user)
		(27 "Margin" user)
		(31 "F.CrtYd" user "F.Courtyard")
		(29 "B.CrtYd" user "B.Courtyard")
		(35 "F.Fab" user)
		(33 "B.Fab" user)
	)
	(footprint "antmicro-footprints:FCBGA-503_22x22mm_Layout21x24_P1mm"
		(locked yes)
		(layer "F.Cu")
		(at 84.975 100 180)
		(property "Reference" "U9"
			(at -11.275 11.4 0)
			(layer "F.SilkS")
			(effects
				(font
					(size 0.7 0.7)
					(thickness 0.15)
				)
				(justify right bottom)
			)
		)
		(property "Value" "EZX710AT2_S_LMR5"
			(at -11.4 12.5 0)
			(layer "F.Fab")
			(hide yes)
			(effects
				(font
					(size 0.7 0.7)
					(thickness 0.15)
				)
				(justify right top)
			)
		)
		(property "Datasheet" "https://www.google.com/url?sa=t&source=web&rct=j&opi=89978449&url=https://cdrdv2-public.intel.com/596333/596333_X710-TM4_Datasheet_v_2_4.pdf&ved=2ahUKEwiSuv20_sCOAxXVCRAIHdxGO_UQFnoECBEQAQ&usg=AOvVaw1CjGyrGWE8ZvOdw4VBsY6U"
			(at -16.625 -13.91 0)
			(layer "F.Fab")
			(hide yes)
			(effects
				(font
					(size 0.7 0.7)
					(thickness 0.15)
				)
				(justify right top)
			)
		)
		(property "Description" "Ethernet ICs Intel Ethernet Controller 10 Gigabit X7"
			(at -12.015 -0.89 0)
			(layer "F.Fab")
			(hide yes)
			(effects
				(font
					(size 0.7 0.7)
					(thickness 0.15)
				)
				(justify right top)
			)
		)
		(property "MPN" "EZX710AT2 S LMR5"
			(at 0 0 180)
			(unlocked yes)
			(layer "F.Fab")
			(hide yes)
			(effects
				(font
					(size 1 1)
					(thickness 0.15)
				)
			)
		)
		(property "Manufacturer" "Intel"
			(at 0 0 180)
			(unlocked yes)
			(layer "F.Fab")
			(hide yes)
			(effects
				(font
					(size 1 1)
					(thickness 0.15)
				)
			)
		)
		(property "Author" "Antmicro"
			(at 0 0 180)
			(unlocked yes)
			(layer "F.Fab")
			(hide yes)
			(effects
				(font
					(size 1 1)
					(thickness 0.15)
				)
			)
		)
		(property "License" "Apache-2.0"
			(at 0 0 180)
			(unlocked yes)
			(layer "F.Fab")
			(hide yes)
			(effects
				(font
					(size 1 1)
					(thickness 0.15)
				)
			)
		)
		(sheetname "/X710-AT2 power/")
		(sheetfile "x710-at2-power.kicad_sch")
		(attr smd)
		(pad "T6" smd circle
			(at -7.75 3.025 180)
			(size 0.5 0.5)
			(layers "F.Cu" "F.Mask" "F.Paste")
			(net 87 "/2xRJ45/~{P1_LED_LINK_10G}")
			(pinfunction "LED2_1")
			(pintype "output")
		)
		(pad "T8" smd circle
			(at -6.75 3.025 180)
			(size 0.5 0.5)
			(layers "F.Cu" "F.Mask" "F.Paste")
			(net 9 "VCCD")
			(pinfunction "RSVDT8_VCCD")
			(pintype "passive")
		)
		(pad "T10" smd circle
			(at -5.75 3.025 180)
			(size 0.5 0.5)
			(layers "F.Cu" "F.Mask" "F.Paste")
			(net 28 "GND")
			(pinfunction "VSS")
			(pintype "passive")
		)
		(pad "T12" smd circle
			(at -4.75 3.025 180)
			(size 0.5 0.5)
			(layers "F.Cu" "F.Mask" "F.Paste")
			(net 28 "GND")
			(pinfunction "VSS")
			(pintype "passive")
		)
		(pad "T14" smd circle
			(at -3.75 3.025 180)
			(size 0.5 0.5)
			(layers "F.Cu" "F.Mask" "F.Paste")
			(net 28 "GND")
			(pinfunction "VSS")
			(pintype "passive")
		)
		(pad "T16" smd circle
			(at -2.75 3.025 180)
			(size 0.5 0.5)
			(layers "F.Cu" "F.Mask" "F.Paste")
			(net 28 "GND")
			(pinfunction "VSS")
			(pintype "passive")
		)
		(pad "T18" smd circle
			(at -1.75 3.025 180)
			(size 0.5 0.5)
			(layers "F.Cu" "F.Mask" "F.Paste")
			(net 28 "GND")
			(pinfunction "VSS")
			(pintype "passive")
		)
		(pad "T20" smd circle
			(at -0.75 3.025 180)
			(size 0.5 0.5)
			(layers "F.Cu" "F.Mask" "F.Paste")
			(net 28 "GND")
			(pinfunction "VSS")
			(pintype "passive")
		)
		(pad "T22" smd circle
			(at 0.25 3.025 180)
			(size 0.5 0.5)
			(layers "F.Cu" "F.Mask" "F.Paste")
			(net 171 "unconnected-(U9E-RSVDT22_NC-PadT22)")
			(pinfunction "RSVDT22_NC")
			(pintype "passive+no_connect")
		)
		(pad "T24" smd circle
			(at 1.25 3.025 180)
			(size 0.5 0.5)
			(layers "F.Cu" "F.Mask" "F.Paste")
			(net 204 "unconnected-(U9E-RSVDT24_NC-PadT24)")
			(pinfunction "RSVDT24_NC")
			(pintype "passive+no_connect")
		)
		(pad "T26" smd circle
			(at 2.25 3.025 180)
			(size 0.5 0.5)
			(layers "F.Cu" "F.Mask" "F.Paste")
			(net 201 "unconnected-(U9E-RSVDT26_NC-PadT26)")
			(pinfunction "RSVDT26_NC")
			(pintype "passive+no_connect")
		)
		(pad "T28" smd circle
			(at 3.25 3.025 180)
			(size 0.5 0.5)
			(layers "F.Cu" "F.Mask" "F.Paste")
			(net 163 "unconnected-(U9E-RSVDT28_NC-PadT28)")
			(pinfunction "RSVDT28_NC")
			(pintype "passive+no_connect")
		)
		(pad "T30" smd circle
			(at 4.25 3.025 180)
			(size 0.5 0.5)
			(layers "F.Cu" "F.Mask" "F.Paste")
			(net 190 "unconnected-(U9G-RSVDT30_NC-PadT30)")
			(pinfunction "RSVDT30_NC")
			(pintype "passive+no_connect")
		)
		(pad "T32" smd circle
			(at 5.25 3.025 180)
			(size 0.5 0.5)
			(layers "F.Cu" "F.Mask" "F.Paste")
			(net 297 "unconnected-(U9G-RSVDT32_NC-PadT32)")
			(pinfunction "RSVDT32_NC")
			(pintype "passive+no_connect")
		)
		(pad "T34" smd circle
			(at 6.25 3.025 180)
			(size 0.5 0.5)
			(layers "F.Cu" "F.Mask" "F.Paste")
			(net 7 "+3V3")
			(pinfunction "VCC3P3")
			(pintype "passive")
		)
		(pad "T36" smd circle
			(at 7.25 3.025 180)
			(size 0.5 0.5)
			(layers "F.Cu" "F.Mask" "F.Paste")
			(net 11 "/X710-AT2 PCIe/PCIe_JTAG.JTDI")
			(pinfunction "JTDI")
			(pintype "input")
		)
		(pad "T38" smd circle
			(at 8.25 3.025 180)
			(size 0.5 0.5)
			(layers "F.Cu" "F.Mask" "F.Paste")
			(net 8 "/X710-AT2 PCIe/PCIe_JTAG.JTDO")
			(pinfunction "JTDO")
			(pintype "open_collector")
		)
		(pad "T40" smd circle
			(at 9.25 3.025 180)
			(size 0.5 0.5)
			(layers "F.Cu" "F.Mask" "F.Paste")
			(net 395 "/OCuLink/SMBus.SDA")
			(pinfunction "SMBD")
			(pintype "open_collector")
		)
		(pad "T42" smd circle
			(at 10.25 3.025 180)
			(size 0.5 0.5)
			(layers "F.Cu" "F.Mask" "F.Paste")
			(net 140 "/Flash memory/FLASH.MISO")
			(pinfunction "FLSH_SO")
			(pintype "input")
		)
		(pad "U1" smd circle
			(at -10.25 3.89 180)
			(size 0.5 0.5)
			(layers "F.Cu" "F.Mask" "F.Paste")
			(net 28 "GND")
			(pinfunction "VSS_SVR")
			(pintype "power_in")
		)
		(pad "U3" smd circle
			(at -9.25 3.89 180)
			(size 0.5 0.5)
			(layers "F.Cu" "F.Mask" "F.Paste")
			(net 289 "/X710-AT2 Misc/~{PCI_DIS}")
			(pinfunction "~{PCI_DIS}")
			(pintype "tri_state")
		)
		(pad "U5" smd circle
			(at -8.25 3.89 180)
			(size 0.5 0.5)
			(layers "F.Cu" "F.Mask" "F.Paste")
			(net 241 "unconnected-(U9C-LED1_0-PadU5)")
			(pinfunction "LED1_0")
			(pintype "passive+no_connect")
		)
		(pad "U7" smd circle
			(at -7.25 3.89 180)
			(size 0.5 0.5)
			(layers "F.Cu" "F.Mask" "F.Paste")
			(net 269 "unconnected-(U9C-LED1_1-PadU7)")
			(pinfunction "LED1_1")
			(pintype "passive+no_connect")
		)
		(pad "U9" smd circle
			(at -6.25 3.89 180)
			(size 0.5 0.5)
			(layers "F.Cu" "F.Mask" "F.Paste")
			(net 193 "unconnected-(U9E-RSVDU9_NC-PadU9)")
			(pinfunction "RSVDU9_NC")
			(pintype "passive+no_connect")
		)
		(pad "U11" smd circle
			(at -5.25 3.89 180)
			(size 0.5 0.5)
			(layers "F.Cu" "F.Mask" "F.Paste")
			(net 9 "VCCD")
			(pinfunction "VCCD")
			(pintype "passive")
		)
		(pad "U13" smd circle
			(at -4.25 3.89 180)
			(size 0.5 0.5)
			(layers "F.Cu" "F.Mask" "F.Paste")
			(net 9 "VCCD")
			(pinfunction "VCCD")
			(pintype "passive")
		)
		(pad "U15" smd circle
			(at -3.25 3.89 180)
			(size 0.5 0.5)
			(layers "F.Cu" "F.Mask" "F.Paste")
			(net 9 "VCCD")
			(pinfunction "VCCD")
			(pintype "passive")
		)
		(pad "U17" smd circle
			(at -2.25 3.89 180)
			(size 0.5 0.5)
			(layers "F.Cu" "F.Mask" "F.Paste")
			(net 9 "VCCD")
			(pinfunction "VCCD")
			(pintype "passive")
		)
		(pad "U19" smd circle
			(at -1.25 3.89 180)
			(size 0.5 0.5)
			(layers "F.Cu" "F.Mask" "F.Paste")
			(net 9 "VCCD")
			(pinfunction "VCCD")
			(pintype "passive")
		)
		(pad "U21" smd circle
			(at -0.25 3.89 180)
			(size 0.5 0.5)
			(layers "F.Cu" "F.Mask" "F.Paste")
			(net 7 "+3V3")
			(pinfunction "VCC3P3")
			(pintype "power_in")
		)
		(pad "U23" smd circle
			(at 0.75 3.89 180)
			(size 0.5 0.5)
			(layers "F.Cu" "F.Mask" "F.Paste")
			(net 222 "unconnected-(U9E-RSVDU23_NC-PadU23)")
			(pinfunction "RSVDU23_NC")
			(pintype "passive+no_connect")
		)
		(pad "U25" smd circle
			(at 1.75 3.89 180)
			(size 0.5 0.5)
			(layers "F.Cu" "F.Mask" "F.Paste")
			(net 280 "unconnected-(U9E-RSVDU25_NC-PadU25)")
			(pinfunction "RSVDU25_NC")
			(pintype "passive+no_connect")
		)
		(pad "U27" smd circle
			(at 2.75 3.89 180)
			(size 0.5 0.5)
			(layers "F.Cu" "F.Mask" "F.Paste")
			(net 261 "unconnected-(U9E-RSVDU27_NC-PadU27)")
			(pinfunction "RSVDU27_NC")
			(pintype "passive+no_connect")
		)
		(pad "U29" smd circle
			(at 3.75 3.89 180)
			(size 0.5 0.5)
			(layers "F.Cu" "F.Mask" "F.Paste")
			(net 184 "unconnected-(U9E-RSVDU29_NC-PadU29)")
			(pinfunction "RSVDU29_NC")
			(pintype "passive+no_connect")
		)
		(pad "U31" smd circle
			(at 4.75 3.89 180)
			(size 0.5 0.5)
			(layers "F.Cu" "F.Mask" "F.Paste")
			(net 173 "unconnected-(U9G-RSVDU31_NC-PadU31)")
			(pinfunction "RSVDU31_NC")
			(pintype "passive+no_connect")
		)
		(pad "U33" smd circle
			(at 5.75 3.89 180)
			(size 0.5 0.5)
			(layers "F.Cu" "F.Mask" "F.Paste")
			(net 232 "unconnected-(U9G-RSVDU33_NC-PadU33)")
			(pinfunction "RSVDU33_NC")
			(pintype "passive+no_connect")
		)
		(pad "U35" smd circle
			(at 6.75 3.89 180)
			(size 0.5 0.5)
			(layers "F.Cu" "F.Mask" "F.Paste")
			(net 167 "unconnected-(U9G-RSVDU35_NC-PadU35)")
			(pinfunction "RSVDU35_NC")
			(pintype "passive+no_connect")
		)
		(pad "U37" smd circle
			(at 7.75 3.89 180)
			(size 0.5 0.5)
			(layers "F.Cu" "F.Mask" "F.Paste")
			(net 16 "/X710-AT2 PCIe/PCIe_JTAG.JTCK")
			(pinfunction "JTCK")
			(pintype "input")
		)
		(pad "U39" smd circle
			(at 8.75 3.89 180)
			(size 0.5 0.5)
			(layers "F.Cu" "F.Mask" "F.Paste")
			(net 47 "/X710-AT2 Misc/POR_BYPASS")
			(pinfunction "POR_BYPASS")
			(pintype "input")
		)
		(pad "U41" smd circle
			(at 9.75 3.89 180)
			(size 0.5 0.5)
			(layers "F.Cu" "F.Mask" "F.Paste")
			(net 97 "/X710-AT2 Misc/~{SMBALRT}")
			(pinfunction "~{SMBALRT}")
			(pintype "open_collector")
		)
		(pad "V2" smd circle
			(at -9.75 4.755 180)
			(size 0.5 0.5)
			(layers "F.Cu" "F.Mask" "F.Paste")
			(net 155 "Net-(U9H-SVR_IND)")
			(pinfunction "SVR_IND")
			(pintype "passive")
		)
		(pad "V4" smd circle
			(at -8.75 4.755 180)
			(size 0.5 0.5)
			(layers "F.Cu" "F.Mask" "F.Paste")
			(net 82 "/2xRJ45/~{P0_LED_ACT}")
			(pinfunction "LED0_0")
			(pintype "output")
		)
		(pad "V6" smd circle
			(at -7.75 4.755 180)
			(size 0.5 0.5)
			(layers "F.Cu" "F.Mask" "F.Paste")
			(net 81 "/2xRJ45/~{P0_LED_LINK_10G}")
			(pinfunction "LED0_1")
			(pintype "output")
		)
		(pad "V8" smd circle
			(at -6.75 4.755 180)
			(size 0.5 0.5)
			(layers "F.Cu" "F.Mask" "F.Paste")
			(net 210 "unconnected-(U9H-RSVDV8_NC-PadV8)")
			(pinfunction "RSVDV8_NC")
			(pintype "passive+no_connect")
		)
		(pad "V10" smd circle
			(at -5.75 4.755 180)
			(size 0.5 0.5)
			(layers "F.Cu" "F.Mask" "F.Paste")
			(net 240 "unconnected-(U9H-RSVDV10_NC-PadV10)")
			(pinfunction "RSVDV10_NC")
			(pintype "passive+no_connect")
		)
		(pad "V12" smd circle
			(at -4.75 4.755 180)
			(size 0.5 0.5)
			(layers "F.Cu" "F.Mask" "F.Paste")
			(net 28 "GND")
			(pinfunction "VSSA")
			(pintype "passive")
		)
		(pad "V14" smd circle
			(at -3.75 4.755 180)
			(size 0.5 0.5)
			(layers "F.Cu" "F.Mask" "F.Paste")
			(net 28 "GND")
			(pinfunction "VSSA")
			(pintype "passive")
		)
		(pad "V16" smd circle
			(at -2.75 4.755 180)
			(size 0.5 0.5)
			(layers "F.Cu" "F.Mask" "F.Paste")
			(net 28 "GND")
			(pinfunction "VSSA")
			(pintype "passive")
		)
		(pad "V18" smd circle
			(at -1.75 4.755 180)
			(size 0.5 0.5)
			(layers "F.Cu" "F.Mask" "F.Paste")
			(net 28 "GND")
			(pinfunction "VSSA")
			(pintype "passive")
		)
		(pad "V20" smd circle
			(at -0.75 4.755 180)
			(size 0.5 0.5)
			(layers "F.Cu" "F.Mask" "F.Paste")
			(net 28 "GND")
			(pinfunction "VSSA")
			(pintype "passive")
		)
		(pad "V22" smd circle
			(at 0.25 4.755 180)
			(size 0.5 0.5)
			(layers "F.Cu" "F.Mask" "F.Paste")
			(net 181 "unconnected-(U9E-RSVDV22_NC-PadV22)")
			(pinfunction "RSVDV22_NC")
			(pintype "passive+no_connect")
		)
		(pad "V24" smd circle
			(at 1.25 4.755 180)
			(size 0.5 0.5)
			(layers "F.Cu" "F.Mask" "F.Paste")
			(net 233 "unconnected-(U9E-RSVDV24_NC-PadV24)")
			(pinfunction "RSVDV24_NC")
			(pintype "passive+no_connect")
		)
		(pad "V26" smd circle
			(at 2.25 4.755 180)
			(size 0.5 0.5)
			(layers "F.Cu" "F.Mask" "F.Paste")
			(net 344 "unconnected-(U9E-RSVDV26_NC-PadV26)")
			(pinfunction "RSVDV26_NC")
			(pintype "passive+no_connect")
		)
		(pad "V28" smd circle
			(at 3.25 4.755 180)
			(size 0.5 0.5)
			(layers "F.Cu" "F.Mask" "F.Paste")
			(net 217 "unconnected-(U9E-RSVDV28_NC-PadV28)")
			(pinfunction "RSVDV28_NC")
			(pintype "passive+no_connect")
		)
		(pad "V30" smd circle
			(at 4.25 4.755 180)
			(size 0.5 0.5)
			(layers "F.Cu" "F.Mask" "F.Paste")
			(net 306 "unconnected-(U9G-RSVDV30_NC-PadV30)")
			(pinfunction "RSVDV30_NC")
			(pintype "passive+no_connect")
		)
		(pad "V32" smd circle
			(at 5.25 4.755 180)
			(size 0.5 0.5)
			(layers "F.Cu" "F.Mask" "F.Paste")
			(net 183 "unconnected-(U9G-RSVDV32_NC-PadV32)")
			(pinfunction "RSVDV32_NC")
			(pintype "passive+no_connect")
		)
		(pad "V34" smd circle
			(at 6.25 4.755 180)
			(size 0.5 0.5)
			(layers "F.Cu" "F.Mask" "F.Paste")
			(net 257 "unconnected-(U9G-RSVDV34_NC-PadV34)")
			(pinfunction "RSVDV34_NC")
			(pintype "passive+no_connect")
		)
		(pad "V36" smd circle
			(at 7.25 4.755 180)
			(size 0.5 0.5)
			(layers "F.Cu" "F.Mask" "F.Paste")
			(net 15 "/X710-AT2 PCIe/PCIe_JTAG.~{JRST}")
			(pinfunction "~{JRST}")
			(pintype "input")
		)
		(pad "V38" smd circle
			(at 8.25 4.755 180)
			(size 0.5 0.5)
			(layers "F.Cu" "F.Mask" "F.Paste")
			(net 4 "/X710-AT2 PCIe/PCIe_JTAG.JTMS")
			(pinfunction "JTMS")
			(pintype "input")
		)
		(pad "V40" smd circle
			(at 9.25 4.755 180)
			(size 0.5 0.5)
			(layers "F.Cu" "F.Mask" "F.Paste")
			(net 291 "/2xRJ45/~{P0_LINK_LESS_THAN_10G}")
			(pinfunction "GPIO_0")
			(pintype "tri_state")
		)
		(pad "V42" smd circle
			(at 10.25 4.755 180)
			(size 0.5 0.5)
			(layers "F.Cu" "F.Mask" "F.Paste")
			(net 263 "unconnected-(U9D-GPIO_3-PadV42)")
			(pinfunction "GPIO_3")
			(pintype "passive+no_connect")
		)
		(pad "W1" smd circle
			(at -10.25 5.62 180)
			(size 0.5 0.5)
			(layers "F.Cu" "F.Mask" "F.Paste")
			(net 126 "/X710-AT2 RSVD/RSVDW1_VSS")
			(pinfunction "RSVDW1_VSS")
			(pintype "passive")
		)
		(pad "W3" smd circle
			(at -9.25 5.62 180)
			(size 0.5 0.5)
			(layers "F.Cu" "F.Mask" "F.Paste")
			(net 28 "GND")
			(pinfunction "RSVDW3_VSS")
			(pintype "power_in")
		)
		(pad "W5" smd circle
			(at -8.25 5.62 180)
			(size 0.5 0.5)
			(layers "F.Cu" "F.Mask" "F.Paste")
			(net 124 "/X710-AT2 RSVD/RSVDW5_VSS")
			(pinfunction "RSVDW5_VSS")
			(pintype "passive")
		)
		(pad "W7" smd circle
			(at -7.25 5.62 180)
			(size 0.5 0.5)
			(layers "F.Cu" "F.Mask" "F.Paste")
			(net 120 "/X710-AT2 RSVD/DEBUG_W7")
			(pinfunction "DEBUG_W7")
			(pintype "passive")
		)
		(pad "W9" smd circle
			(at -6.25 5.62 180)
			(size 0.5 0.5)
			(layers "F.Cu" "F.Mask" "F.Paste")
			(net 9 "VCCD")
			(pinfunction "VCCD_A")
			(pintype "power_in")
		)
		(pad "W11" smd circle
			(at -5.25 5.62 180)
			(size 0.5 0.5)
			(layers "F.Cu" "F.Mask" "F.Paste")
			(net 7 "+3V3")
			(pinfunction "VCC3P3_A")
			(pintype "power_in")
		)
		(pad "W13" smd circle
			(at -4.25 5.62 180)
			(size 0.5 0.5)
			(layers "F.Cu" "F.Mask" "F.Paste")
			(net 1 "VCCA")
			(pinfunction "VCCA")
			(pintype "passive")
		)
		(pad "W15" smd circle
			(at -3.25 5.62 180)
			(size 0.5 0.5)
			(layers "F.Cu" "F.Mask" "F.Paste")
			(net 1 "VCCA")
			(pinfunction "VCCA")
			(pintype "passive")
		)
		(pad "W17" smd circle
			(at -2.25 5.62 180)
			(size 0.5 0.5)
			(layers "F.Cu" "F.Mask" "F.Paste")
			(net 1 "VCCA")
			(pinfunction "VCCA")
			(pintype "passive")
		)
		(pad "W19" smd circle
			(at -1.25 5.62 180)
			(size 0.5 0.5)
			(layers "F.Cu" "F.Mask" "F.Paste")
			(net 1 "VCCA")
			(pinfunction "VCCA")
			(pintype "passive")
		)
		(pad "W21" smd circle
			(at -0.25 5.62 180)
			(size 0.5 0.5)
			(layers "F.Cu" "F.Mask" "F.Paste")
			(net 1 "VCCA")
			(pinfunction "VCCA")
			(pintype "passive")
		)
		(pad "W23" smd circle
			(at 0.75 5.62 180)
			(size 0.5 0.5)
			(layers "F.Cu" "F.Mask" "F.Paste")
			(net 206 "unconnected-(U9E-RSVDW23_NC-PadW23)")
			(pinfunction "RSVDW23_NC")
			(pintype "passive+no_connect")
		)
		(pad "W25" smd circle
			(at 1.75 5.62 180)
			(size 0.5 0.5)
			(layers "F.Cu" "F.Mask" "F.Paste")
			(net 194 "unconnected-(U9E-RSVDW25_NC-PadW25)")
			(pinfunction "RSVDW25_NC")
			(pintype "passive+no_connect")
		)
		(pad "W27" smd circle
			(at 2.75 5.62 180)
			(size 0.5 0.5)
			(layers "F.Cu" "F.Mask" "F.Paste")
			(net 179 "unconnected-(U9E-RSVDW27_NC-PadW27)")
			(pinfunction "RSVDW27_NC")
			(pintype "passive+no_connect")
		)
		(pad "W29" smd circle
			(at 3.75 5.62 180)
			(size 0.5 0.5)
			(layers "F.Cu" "F.Mask" "F.Paste")
			(net 28 "GND")
			(pinfunction "VSSA")
			(pintype "passive")
		)
		(pad "W31" smd circle
			(at 4.75 5.62 180)
			(size 0.5 0.5)
			(layers "F.Cu" "F.Mask" "F.Paste")
			(net 28 "GND")
			(pinfunction "VSSA")
			(pintype "passive")
		)
		(pad "W33" smd circle
			(at 5.75 5.62 180)
			(size 0.5 0.5)
			(layers "F.Cu" "F.Mask" "F.Paste")
			(net 28 "GND")
			(pinfunction "VSSA")
			(pintype "passive")
		)
		(pad "W35" smd circle
			(at 6.75 5.62 180)
			(size 0.5 0.5)
			(layers "F.Cu" "F.Mask" "F.Paste")
			(net 28 "GND")
			(pinfunction "VSSA")
			(pintype "passive")
		)
	)
)
